# T6G (Grand Teton) — schematic netlist excerpt (pin names and nets, part order shuffled) for the footprints in the layout excerpt that follows; sources: Cadence DE-HDL packaged netlist, KiCad conversion of 04192023_DAF0TMB3IC0_F0TG_MB_C_brd_V02_OCP.brd

C1134  Q_CAP  0.1UF 16V 10% X7R  pkg C0402  page 83 : A = P1V8_AUX ; B = GND
C2280  Q_CAP  22UF 4V 20% X6S  pkg C0402  page 72 : A = PVDDCR_SOC_P1 ; B = GND

(kicad_pcb
	(version 20260206)
	(generator "pcbnew")
	(generator_version "10.0")
	(general
		(thickness 1.6)
		(legacy_teardrops no)
	)
	(paper "A4")
	(title_block
		(title "04192023_DAF0TMB3IC0_F0TG_MB_C_brd_V02_OCP.brd")
		(comment 1 "Grand Teton / footprints 6252-6253 of 8354")
	)
	(layers
		(0 "F.Cu" signal "TOP")
		(4 "In1.Cu" signal "GND")
		(6 "In2.Cu" signal "IN1")
		(8 "In3.Cu" signal "GND1")
		(10 "In4.Cu" signal "IN2")
		(12 "In5.Cu" signal "GND2")
		(14 "In6.Cu" signal "IN3")
		(16 "In7.Cu" signal "GND3")
		(18 "In8.Cu" signal "VCC")
		(20 "In9.Cu" signal "VCC1")
		(22 "In10.Cu" signal "GND4")
		(24 "In11.Cu" signal "IN4")
		(26 "In12.Cu" signal "GND5")
		(28 "In13.Cu" signal "IN5")
		(30 "In14.Cu" signal "GND6")
		(32 "In15.Cu" signal "IN6")
		(34 "In16.Cu" signal "GND7")
		(2 "B.Cu" signal "BOTTOM")
		(9 "F.Adhes" user "F.Adhesive")
		(11 "B.Adhes" user "B.Adhesive")
		(13 "F.Paste" user "Package Geometry/Pastemask Top")
		(15 "B.Paste" user "Package Geometry/Pastemask Bottom")
		(5 "F.SilkS" user "Ref Des/Silkscreen Top")
		(7 "B.SilkS" user "Ref Des/Silkscreen Bottom")
		(1 "F.Mask" user "Board Geometry/Soldermask Top")
		(3 "B.Mask" user "Board Geometry/Soldermask Bottom")
		(17 "Dwgs.User" user "User.Drawings")
		(19 "Cmts.User" user "User.Comments")
		(21 "Eco1.User" user "User.Eco1")
		(23 "Eco2.User" user "User.Eco2")
		(25 "Edge.Cuts" user "Board Geometry/Outline")
		(27 "Margin" user)
		(31 "F.CrtYd" user "Package Geometry/Place Bound Top")
		(29 "B.CrtYd" user "Package Geometry/Place Bound Bottom")
		(35 "F.Fab" user "Ref Des/Assembly Top")
		(33 "B.Fab" user "Ref Des/Assembly Bottom")
	)
	(footprint ""
		(layer "B.Cu")
		(at 119.293386 -253.432564)
		(property "Reference" "C2280"
			(at 0 0 0)
			(layer "B.SilkS")
			(hide yes)
			(effects
				(font
					(size 1.27 1.27)
				)
				(justify mirror)
			)
		)
		(property "Value" ""
			(at 0 0 0)
			(layer "B.Fab")
			(effects
				(font
					(size 1.27 1.27)
				)
				(justify mirror)
			)
		)
		(duplicate_pad_numbers_are_jumpers no)
		(fp_line
			(start -0.7874 -0.4064)
			(end -0.7874 0.4064)
			(stroke
				(width 0.1524)
				(type default)
			)
			(layer "B.SilkS")
		)
		(fp_line
			(start -0.7874 0.4064)
			(end 0.7874 0.4064)
			(stroke
				(width 0.1524)
				(type default)
			)
			(layer "B.SilkS")
		)
		(fp_line
			(start 0.7874 -0.4064)
			(end -0.7874 -0.4064)
			(stroke
				(width 0.1524)
				(type default)
			)
			(layer "B.SilkS")
		)
		(fp_line
			(start 0.7874 0.4064)
			(end 0.7874 -0.4064)
			(stroke
				(width 0.1524)
				(type default)
			)
			(layer "B.SilkS")
		)
		(fp_line
			(start -0.67945 -0.3048)
			(end -0.67945 0.3048)
			(stroke
				(width 0.1)
				(type default)
			)
			(layer "B.Fab")
		)
		(fp_line
			(start -0.67945 0.3048)
			(end -0.120396 0.3048)
			(stroke
				(width 0.1)
				(type default)
			)
			(layer "B.Fab")
		)
		(fp_line
			(start -0.12065 -0.3048)
			(end -0.67945 -0.3048)
			(stroke
				(width 0.1)
				(type default)
			)
			(layer "B.Fab")
		)
		(fp_line
			(start -0.12065 -0.2794)
			(end -0.12065 -0.3048)
			(stroke
				(width 0.1)
				(type default)
			)
			(layer "B.Fab")
		)
		(fp_line
			(start -0.120396 0.2794)
			(end 0.12065 0.2794)
			(stroke
				(width 0.1)
				(type default)
			)
			(layer "B.Fab")
		)
		(fp_line
			(start -0.120396 0.3048)
			(end -0.120396 0.2794)
			(stroke
				(width 0.1)
				(type default)
			)
			(layer "B.Fab")
		)
		(fp_line
			(start 0.12065 -0.305054)
			(end 0.12065 -0.2794)
			(stroke
				(width 0.1)
				(type default)
			)
			(layer "B.Fab")
		)
		(fp_line
			(start 0.12065 -0.2794)
			(end -0.12065 -0.2794)
			(stroke
				(width 0.1)
				(type default)
			)
			(layer "B.Fab")
		)
		(fp_line
			(start 0.12065 0.2794)
			(end 0.12065 0.3048)
			(stroke
				(width 0.1)
				(type default)
			)
			(layer "B.Fab")
		)
		(fp_line
			(start 0.12065 0.3048)
			(end 0.67945 0.3048)
			(stroke
				(width 0.1)
				(type default)
			)
			(layer "B.Fab")
		)
		(fp_line
			(start 0.67945 -0.305054)
			(end 0.12065 -0.305054)
			(stroke
				(width 0.1)
				(type default)
			)
			(layer "B.Fab")
		)
		(fp_line
			(start 0.67945 0.3048)
			(end 0.67945 -0.305054)
			(stroke
				(width 0.1)
				(type default)
			)
			(layer "B.Fab")
		)
		(pad "1" smd circle
			(at 0.40005 0 180)
			(size 0 0)
			(layers "B.Cu" "B.Mask" "B.Paste")
			(net "PVDDCR_SOC_P1")
		)
		(pad "2" smd circle
			(at -0.40005 0 180)
			(size 0 0)
			(layers "B.Cu" "B.Mask" "B.Paste")
			(net "GND")
		)
	)
	(footprint ""
		(layer "B.Cu")
		(at 185.458608 -118.242842 90)
		(property "Reference" "C1134"
			(at 0 0 90)
			(layer "B.SilkS")
			(hide yes)
			(effects
				(font
					(size 1.27 1.27)
				)
				(justify mirror)
			)
		)
		(property "Value" ""
			(at 0 0 90)
			(layer "B.Fab")
			(effects
				(font
					(size 1.27 1.27)
				)
				(justify mirror)
			)
		)
		(duplicate_pad_numbers_are_jumpers no)
		(fp_line
			(start 0.69215 -0.2921)
			(end -0.69215 -0.2921)
			(stroke
				(width 0.1524)
				(type default)
			)
			(layer "B.SilkS")
		)
		(fp_line
			(start -0.69215 -0.2921)
			(end -0.69215 0.2921)
			(stroke
				(width 0.1524)
				(type default)
			)
			(layer "B.SilkS")
		)
		(fp_line
			(start 0.69215 0.2921)
			(end 0.69215 -0.2921)
			(stroke
				(width 0.1524)
				(type default)
			)
			(layer "B.SilkS")
		)
		(fp_line
			(start -0.69215 0.2921)
			(end 0.69215 0.2921)
			(stroke
				(width 0.1524)
				(type default)
			)
			(layer "B.SilkS")
		)
		(fp_line
			(start 0.51435 -0.2794)
			(end -0.51435 -0.2794)
			(stroke
				(width 0.1)
				(type default)
			)
			(layer "B.Fab")
		)
		(fp_line
			(start -0.51435 -0.2794)
			(end -0.51435 0.2794)
			(stroke
				(width 0.1)
				(type default)
			)
			(layer "B.Fab")
		)
		(fp_line
			(start 0.51435 0.2794)
			(end 0.51435 -0.2794)
			(stroke
				(width 0.1)
				(type default)
			)
			(layer "B.Fab")
		)
		(fp_line
			(start -0.51435 0.2794)
			(end 0.51435 0.2794)
			(stroke
				(width 0.1)
				(type default)
			)
			(layer "B.Fab")
		)
		(pad "1" smd circle
			(at 0.40005 0 270)
			(size 0 0)
			(layers "B.Cu" "B.Mask" "B.Paste")
			(net "P1V8_AUX")
		)
		(pad "2" smd circle
			(at -0.40005 0 270)
			(size 0 0)
			(layers "B.Cu" "B.Mask" "B.Paste")
			(net "GND")
		)
		(zone
			(layer "B.Cu")
			(hatch none 0.5)
			(connect_pads
				(clearance 0)
			)
			(min_thickness 0.25)
			(keepout
				(tracks not_allowed)
				(vias allowed)
				(pads allowed)
				(copperpour not_allowed)
				(footprints allowed)
			)
			(placement
				(enabled no)
				(sheetname "")
			)
			(fill
				(thermal_gap 0.5)
				(thermal_bridge_width 0.5)
				(island_removal_mode 0)
			)
			(polygon
				(pts
					(xy 185.312558 -118.142512) (xy 185.312558 -118.341902) (xy 185.370724 -118.433342) (xy 185.546238 -118.433342)
					(xy 185.604404 -118.341902) (xy 185.604404 -118.142512) (xy 185.546238 -118.052342) (xy 185.370978 -118.052342)
				)
			)
		)
	)
)
